(kicad_pcb
	(version 20260206)
	(generator "pcbnew")
	(generator_version "10.0")
	(general
		(thickness 1.6)
		(legacy_teardrops no)
	)
	(paper "A4")
	(title_block
		(title "01162023_DA0F0TEBIF0_F0T_Expander_BD_F_brd_V02_OCP.brd")
		(comment 1 "Grand Teton / footprints 3197-3203 of 9728")
	)
	(layers
		(0 "F.Cu" signal "TOP")
		(4 "In1.Cu" signal "GND")
		(6 "In2.Cu" signal "VCC")
		(8 "In3.Cu" signal "VCC1")
		(10 "In4.Cu" signal "GND1")
		(12 "In5.Cu" signal "IN1")
		(14 "In6.Cu" signal "GND2")
		(16 "In7.Cu" signal "IN2")
		(18 "In8.Cu" signal "GND3")
		(20 "In9.Cu" signal "IN3")
		(22 "In10.Cu" signal "GND4")
		(24 "In11.Cu" signal "IN4")
		(26 "In12.Cu" signal "GND5")
		(28 "In13.Cu" signal "IN5")
		(30 "In14.Cu" signal "GND6")
		(32 "In15.Cu" signal "IN6")
		(34 "In16.Cu" signal "GND7")
		(2 "B.Cu" signal "BOTTOM")
		(9 "F.Adhes" user "F.Adhesive")
		(11 "B.Adhes" user "B.Adhesive")
		(13 "F.Paste" user "Package Geometry/Pastemask Top")
		(15 "B.Paste" user "Package Geometry/Pastemask Bottom")
		(5 "F.SilkS" user "Ref Des/Silkscreen Top")
		(7 "B.SilkS" user "Ref Des/Silkscreen Bottom")
		(1 "F.Mask" user "Board Geometry/Soldermask Top")
		(3 "B.Mask" user "Board Geometry/Soldermask Bottom")
		(17 "Dwgs.User" user "User.Drawings")
		(19 "Cmts.User" user "User.Comments")
		(21 "Eco1.User" user "User.Eco1")
		(23 "Eco2.User" user "User.Eco2")
		(25 "Edge.Cuts" user "Board Geometry/Outline")
		(27 "Margin" user)
		(31 "F.CrtYd" user "Package Geometry/Place Bound Top")
		(29 "B.CrtYd" user "Package Geometry/Place Bound Bottom")
		(35 "F.Fab" user "Ref Des/Assembly Top")
		(33 "B.Fab" user "Ref Des/Assembly Bottom")
	)
	(footprint ""
		(layer "F.Cu")
		(at 279.14727 -19.33956)
		(property "Reference" "C3936"
			(at 0 0 0)
			(layer "F.SilkS")
			(hide yes)
			(effects
				(font
					(size 1.27 1.27)
				)
			)
		)
		(property "Value" ""
			(at 0 0 0)
			(layer "F.Fab")
			(effects
				(font
					(size 1.27 1.27)
				)
			)
		)
		(duplicate_pad_numbers_are_jumpers no)
		(fp_line
			(start -0.7874 -0.4064)
			(end 0.7874 -0.4064)
			(stroke
				(width 0.1524)
				(type default)
			)
			(layer "F.SilkS")
		)
		(fp_line
			(start -0.7874 0.4064)
			(end -0.7874 -0.4064)
			(stroke
				(width 0.1524)
				(type default)
			)
			(layer "F.SilkS")
		)
		(fp_line
			(start 0.7874 -0.4064)
			(end 0.7874 0.4064)
			(stroke
				(width 0.1524)
				(type default)
			)
			(layer "F.SilkS")
		)
		(fp_line
			(start 0.7874 0.4064)
			(end -0.7874 0.4064)
			(stroke
				(width 0.1524)
				(type default)
			)
			(layer "F.SilkS")
		)
		(fp_line
			(start -0.67945 -0.305054)
			(end -0.12065 -0.305054)
			(stroke
				(width 0.1)
				(type default)
			)
			(layer "F.Fab")
		)
		(fp_line
			(start -0.67945 0.3048)
			(end -0.67945 -0.305054)
			(stroke
				(width 0.1)
				(type default)
			)
			(layer "F.Fab")
		)
		(fp_line
			(start -0.12065 -0.305054)
			(end -0.12065 -0.2794)
			(stroke
				(width 0.1)
				(type default)
			)
			(layer "F.Fab")
		)
		(fp_line
			(start -0.12065 -0.2794)
			(end 0.12065 -0.2794)
			(stroke
				(width 0.1)
				(type default)
			)
			(layer "F.Fab")
		)
		(fp_line
			(start -0.12065 0.2794)
			(end -0.12065 0.3048)
			(stroke
				(width 0.1)
				(type default)
			)
			(layer "F.Fab")
		)
		(fp_line
			(start -0.12065 0.3048)
			(end -0.67945 0.3048)
			(stroke
				(width 0.1)
				(type default)
			)
			(layer "F.Fab")
		)
		(fp_line
			(start 0.120396 0.2794)
			(end -0.12065 0.2794)
			(stroke
				(width 0.1)
				(type default)
			)
			(layer "F.Fab")
		)
		(fp_line
			(start 0.120396 0.3048)
			(end 0.120396 0.2794)
			(stroke
				(width 0.1)
				(type default)
			)
			(layer "F.Fab")
		)
		(fp_line
			(start 0.12065 -0.3048)
			(end 0.67945 -0.3048)
			(stroke
				(width 0.1)
				(type default)
			)
			(layer "F.Fab")
		)
		(fp_line
			(start 0.12065 -0.2794)
			(end 0.12065 -0.3048)
			(stroke
				(width 0.1)
				(type default)
			)
			(layer "F.Fab")
		)
		(fp_line
			(start 0.67945 -0.3048)
			(end 0.67945 0.3048)
			(stroke
				(width 0.1)
				(type default)
			)
			(layer "F.Fab")
		)
		(fp_line
			(start 0.67945 0.3048)
			(end 0.120396 0.3048)
			(stroke
				(width 0.1)
				(type default)
			)
			(layer "F.Fab")
		)
		(pad "1" smd circle
			(at -0.40005 0)
			(size 0 0)
			(layers "F.Cu" "F.Mask" "F.Paste")
			(net "P12V_SSD9")
		)
		(pad "2" smd circle
			(at 0.40005 0)
			(size 0 0)
			(layers "F.Cu" "F.Mask" "F.Paste")
			(net "GND")
		)
	)
	(footprint ""
		(layer "F.Cu")
		(at 65.370202 -356.244906 90)
		(property "Reference" "C124"
			(at 0 0 90)
			(layer "F.SilkS")
			(hide yes)
			(effects
				(font
					(size 1.27 1.27)
				)
			)
		)
		(property "Value" ""
			(at 0 0 90)
			(layer "F.Fab")
			(effects
				(font
					(size 1.27 1.27)
				)
			)
		)
		(duplicate_pad_numbers_are_jumpers no)
		(fp_line
			(start 0.299974 -0.150114)
			(end 0.299974 0.150114)
			(stroke
				(width 0.1)
				(type default)
			)
			(layer "F.Fab")
		)
		(fp_line
			(start -0.299974 -0.150114)
			(end 0.299974 -0.150114)
			(stroke
				(width 0.1)
				(type default)
			)
			(layer "F.Fab")
		)
		(fp_line
			(start 0.299974 0.150114)
			(end -0.299974 0.150114)
			(stroke
				(width 0.1)
				(type default)
			)
			(layer "F.Fab")
		)
		(fp_line
			(start -0.299974 0.150114)
			(end -0.299974 -0.150114)
			(stroke
				(width 0.1)
				(type default)
			)
			(layer "F.Fab")
		)
		(pad "1" smd rect
			(at -0.2667 0 90)
			(size 0.3048 0.381)
			(layers "F.Cu" "F.Mask" "F.Paste")
			(net "P5E_PEX0_STN5_TX_DN<82>")
		)
		(pad "2" smd rect
			(at 0.2667 0 90)
			(size 0.3048 0.381)
			(layers "F.Cu" "F.Mask" "F.Paste")
			(net "P5E_PEX0_STN5_TX_C_DN<82>")
		)
	)
	(footprint ""
		(layer "F.Cu")
		(at 436.262272 -306.023772 90)
		(property "Reference" "R3993"
			(at 0 0 90)
			(layer "F.SilkS")
			(hide yes)
			(effects
				(font
					(size 1.27 1.27)
				)
			)
		)
		(property "Value" ""
			(at 0 0 90)
			(layer "F.Fab")
			(effects
				(font
					(size 1.27 1.27)
				)
			)
		)
		(duplicate_pad_numbers_are_jumpers no)
		(fp_line
			(start 0.7874 -0.4064)
			(end 0.7874 0.4064)
			(stroke
				(width 0.1524)
				(type default)
			)
			(layer "F.SilkS")
		)
		(fp_line
			(start -0.7874 -0.4064)
			(end 0.7874 -0.4064)
			(stroke
				(width 0.1524)
				(type default)
			)
			(layer "F.SilkS")
		)
		(fp_line
			(start 0.7874 0.4064)
			(end -0.7874 0.4064)
			(stroke
				(width 0.1524)
				(type default)
			)
			(layer "F.SilkS")
		)
		(fp_line
			(start -0.7874 0.4064)
			(end -0.7874 -0.4064)
			(stroke
				(width 0.1524)
				(type default)
			)
			(layer "F.SilkS")
		)
		(fp_line
			(start -0.12065 -0.305054)
			(end -0.12065 -0.2794)
			(stroke
				(width 0.1)
				(type default)
			)
			(layer "F.Fab")
		)
		(fp_line
			(start -0.67945 -0.305054)
			(end -0.12065 -0.305054)
			(stroke
				(width 0.1)
				(type default)
			)
			(layer "F.Fab")
		)
		(fp_line
			(start 0.67945 -0.3048)
			(end 0.67945 0.3048)
			(stroke
				(width 0.1)
				(type default)
			)
			(layer "F.Fab")
		)
		(fp_line
			(start 0.12065 -0.3048)
			(end 0.67945 -0.3048)
			(stroke
				(width 0.1)
				(type default)
			)
			(layer "F.Fab")
		)
		(fp_line
			(start 0.12065 -0.2794)
			(end 0.12065 -0.3048)
			(stroke
				(width 0.1)
				(type default)
			)
			(layer "F.Fab")
		)
		(fp_line
			(start -0.12065 -0.2794)
			(end 0.12065 -0.2794)
			(stroke
				(width 0.1)
				(type default)
			)
			(layer "F.Fab")
		)
		(fp_line
			(start 0.120396 0.2794)
			(end -0.12065 0.2794)
			(stroke
				(width 0.1)
				(type default)
			)
			(layer "F.Fab")
		)
		(fp_line
			(start -0.12065 0.2794)
			(end -0.12065 0.3048)
			(stroke
				(width 0.1)
				(type default)
			)
			(layer "F.Fab")
		)
		(fp_line
			(start 0.67945 0.3048)
			(end 0.120396 0.3048)
			(stroke
				(width 0.1)
				(type default)
			)
			(layer "F.Fab")
		)
		(fp_line
			(start 0.120396 0.3048)
			(end 0.120396 0.2794)
			(stroke
				(width 0.1)
				(type default)
			)
			(layer "F.Fab")
		)
		(fp_line
			(start -0.12065 0.3048)
			(end -0.67945 0.3048)
			(stroke
				(width 0.1)
				(type default)
			)
			(layer "F.Fab")
		)
		(fp_line
			(start -0.67945 0.3048)
			(end -0.67945 -0.305054)
			(stroke
				(width 0.1)
				(type default)
			)
			(layer "F.Fab")
		)
		(pad "1" smd circle
			(at -0.40005 0 90)
			(size 0 0)
			(layers "F.Cu" "F.Mask" "F.Paste")
			(net "SMB_PEX3_SLAVE_SDA")
		)
		(pad "2" smd circle
			(at 0.40005 0 90)
			(size 0 0)
			(layers "F.Cu" "F.Mask" "F.Paste")
			(net "SMB_PEX3_R_SDA")
		)
	)
	(footprint ""
		(layer "F.Cu")
		(at 214.43823 -222.378778 180)
		(property "Reference" "R4884"
			(at 0 0 180)
			(layer "F.SilkS")
			(hide yes)
			(effects
				(font
					(size 1.27 1.27)
				)
			)
		)
		(property "Value" ""
			(at 0 0 180)
			(layer "F.Fab")
			(effects
				(font
					(size 1.27 1.27)
				)
			)
		)
		(duplicate_pad_numbers_are_jumpers no)
		(fp_line
			(start 0.7874 0.4064)
			(end -0.7874 0.4064)
			(stroke
				(width 0.1524)
				(type default)
			)
			(layer "F.SilkS")
		)
		(fp_line
			(start 0.7874 -0.4064)
			(end 0.7874 0.4064)
			(stroke
				(width 0.1524)
				(type default)
			)
			(layer "F.SilkS")
		)
		(fp_line
			(start -0.7874 0.4064)
			(end -0.7874 -0.4064)
			(stroke
				(width 0.1524)
				(type default)
			)
			(layer "F.SilkS")
		)
		(fp_line
			(start -0.7874 -0.4064)
			(end 0.7874 -0.4064)
			(stroke
				(width 0.1524)
				(type default)
			)
			(layer "F.SilkS")
		)
		(fp_line
			(start 0.67945 0.3048)
			(end 0.120396 0.3048)
			(stroke
				(width 0.1)
				(type default)
			)
			(layer "F.Fab")
		)
		(fp_line
			(start 0.67945 -0.3048)
			(end 0.67945 0.3048)
			(stroke
				(width 0.1)
				(type default)
			)
			(layer "F.Fab")
		)
		(fp_line
			(start 0.12065 -0.2794)
			(end 0.12065 -0.3048)
			(stroke
				(width 0.1)
				(type default)
			)
			(layer "F.Fab")
		)
		(fp_line
			(start 0.12065 -0.3048)
			(end 0.67945 -0.3048)
			(stroke
				(width 0.1)
				(type default)
			)
			(layer "F.Fab")
		)
		(fp_line
			(start 0.120396 0.3048)
			(end 0.120396 0.2794)
			(stroke
				(width 0.1)
				(type default)
			)
			(layer "F.Fab")
		)
		(fp_line
			(start 0.120396 0.2794)
			(end -0.12065 0.2794)
			(stroke
				(width 0.1)
				(type default)
			)
			(layer "F.Fab")
		)
		(fp_line
			(start -0.12065 0.3048)
			(end -0.67945 0.3048)
			(stroke
				(width 0.1)
				(type default)
			)
			(layer "F.Fab")
		)
		(fp_line
			(start -0.12065 0.2794)
			(end -0.12065 0.3048)
			(stroke
				(width 0.1)
				(type default)
			)
			(layer "F.Fab")
		)
		(fp_line
			(start -0.12065 -0.2794)
			(end 0.12065 -0.2794)
			(stroke
				(width 0.1)
				(type default)
			)
			(layer "F.Fab")
		)
		(fp_line
			(start -0.12065 -0.305054)
			(end -0.12065 -0.2794)
			(stroke
				(width 0.1)
				(type default)
			)
			(layer "F.Fab")
		)
		(fp_line
			(start -0.67945 0.3048)
			(end -0.67945 -0.305054)
			(stroke
				(width 0.1)
				(type default)
			)
			(layer "F.Fab")
		)
		(fp_line
			(start -0.67945 -0.305054)
			(end -0.12065 -0.305054)
			(stroke
				(width 0.1)
				(type default)
			)
			(layer "F.Fab")
		)
		(pad "1" smd circle
			(at -0.40005 0 180)
			(size 0 0)
			(layers "F.Cu" "F.Mask" "F.Paste")
			(net "SMB_BIC_FPGA_R_SDA")
		)
		(pad "2" smd circle
			(at 0.40005 0 180)
			(size 0 0)
			(layers "F.Cu" "F.Mask" "F.Paste")
			(net "P3V3_AUX")
		)
	)
	(footprint ""
		(layer "F.Cu")
		(at 358.44988 -148.872702)
		(property "Reference" "PD15"
			(at -3.4544 -2.225548 0)
			(unlocked yes)
			(layer "F.SilkS")
			(effects
				(font
					(size 0.7874 0.5842)
					(thickness 0.1524)
				)
				(justify left)
			)
		)
		(property "Value" ""
			(at 0 0 0)
			(layer "F.Fab")
			(effects
				(font
					(size 1.27 1.27)
				)
			)
		)
		(duplicate_pad_numbers_are_jumpers no)
		(fp_line
			(start -3.400044 -1.459992)
			(end 4.107942 -1.459992)
			(stroke
				(width 0.1524)
				(type default)
			)
			(layer "F.SilkS")
		)
		(fp_line
			(start -3.400044 1.459992)
			(end -3.400044 -1.459992)
			(stroke
				(width 0.1524)
				(type default)
			)
			(layer "F.SilkS")
		)
		(fp_line
			(start 4.107942 -1.459992)
			(end 4.107942 1.459992)
			(stroke
				(width 0.1524)
				(type default)
			)
			(layer "F.SilkS")
		)
		(fp_line
			(start 4.107942 1.459992)
			(end -3.400044 1.459992)
			(stroke
				(width 0.1524)
				(type default)
			)
			(layer "F.SilkS")
		)
		(fp_poly
			(pts
				(xy 4.107942 -1.459992) (xy 4.107942 1.459992) (xy 3.308096 1.459992) (xy 3.308096 -1.459992)
			)
			(stroke
				(width 0)
				(type default)
			)
			(fill yes)
			(layer "F.SilkS")
		)
		(fp_line
			(start -2.29997 -1.459992)
			(end 2.29997 -1.459992)
			(stroke
				(width 0.1)
				(type default)
			)
			(layer "F.Fab")
		)
		(fp_line
			(start -2.29997 1.459992)
			(end -2.29997 -1.459992)
			(stroke
				(width 0.1)
				(type default)
			)
			(layer "F.Fab")
		)
		(fp_line
			(start 2.29997 -1.459992)
			(end 2.29997 1.459992)
			(stroke
				(width 0.1)
				(type default)
			)
			(layer "F.Fab")
		)
		(fp_line
			(start 2.29997 1.459992)
			(end -2.29997 1.459992)
			(stroke
				(width 0.1)
				(type default)
			)
			(layer "F.Fab")
		)
		(fp_text user "+"
			(at -4.7752 -0.12065 0)
			(unlocked yes)
			(layer "F.SilkS")
			(effects
				(font
					(size 1.905 1.4224)
					(thickness 0.1524)
				)
				(justify left)
			)
		)
		(fp_text user "-"
			(at 5.4102 0.29845 180)
			(unlocked yes)
			(layer "F.SilkS")
			(effects
				(font
					(size 1.905 1.4224)
					(thickness 0.1524)
				)
				(justify left)
			)
		)
		(fp_text user "+"
			(at -4.7752 -0.12065 0)
			(unlocked yes)
			(layer "F.Fab")
			(effects
				(font
					(size 1.905 1.4224)
					(thickness 0.1524)
				)
				(justify left)
			)
		)
		(fp_text user "-"
			(at 5.4102 0.29845 180)
			(unlocked yes)
			(layer "F.Fab")
			(effects
				(font
					(size 1.905 1.4224)
					(thickness 0.1524)
				)
				(justify left)
			)
		)
		(pad "A" smd rect
			(at -1.999996 0 90)
			(size 1.7018 2.5146)
			(layers "F.Cu" "F.Mask" "F.Paste")
			(net "GND")
		)
		(pad "C" smd rect
			(at 1.999996 0 90)
			(size 1.7018 2.5146)
			(layers "F.Cu" "F.Mask" "F.Paste")
			(net "P12V_NIC6_R")
		)
	)
	(footprint ""
		(layer "F.Cu")
		(at 204.591158 -82.643472)
		(property "Reference" "R4332"
			(at 0 0 0)
			(layer "F.SilkS")
			(hide yes)
			(effects
				(font
					(size 1.27 1.27)
				)
			)
		)
		(property "Value" ""
			(at 0 0 0)
			(layer "F.Fab")
			(effects
				(font
					(size 1.27 1.27)
				)
			)
		)
		(duplicate_pad_numbers_are_jumpers no)
		(fp_line
			(start -0.7874 -0.4064)
			(end 0.7874 -0.4064)
			(stroke
				(width 0.1524)
				(type default)
			)
			(layer "F.SilkS")
		)
		(fp_line
			(start -0.7874 0.4064)
			(end -0.7874 -0.4064)
			(stroke
				(width 0.1524)
				(type default)
			)
			(layer "F.SilkS")
		)
		(fp_line
			(start 0.7874 -0.4064)
			(end 0.7874 0.4064)
			(stroke
				(width 0.1524)
				(type default)
			)
			(layer "F.SilkS")
		)
		(fp_line
			(start 0.7874 0.4064)
			(end -0.7874 0.4064)
			(stroke
				(width 0.1524)
				(type default)
			)
			(layer "F.SilkS")
		)
		(fp_line
			(start -0.67945 -0.305054)
			(end -0.12065 -0.305054)
			(stroke
				(width 0.1)
				(type default)
			)
			(layer "F.Fab")
		)
		(fp_line
			(start -0.67945 0.3048)
			(end -0.67945 -0.305054)
			(stroke
				(width 0.1)
				(type default)
			)
			(layer "F.Fab")
		)
		(fp_line
			(start -0.12065 -0.305054)
			(end -0.12065 -0.2794)
			(stroke
				(width 0.1)
				(type default)
			)
			(layer "F.Fab")
		)
		(fp_line
			(start -0.12065 -0.2794)
			(end 0.12065 -0.2794)
			(stroke
				(width 0.1)
				(type default)
			)
			(layer "F.Fab")
		)
		(fp_line
			(start -0.12065 0.2794)
			(end -0.12065 0.3048)
			(stroke
				(width 0.1)
				(type default)
			)
			(layer "F.Fab")
		)
		(fp_line
			(start -0.12065 0.3048)
			(end -0.67945 0.3048)
			(stroke
				(width 0.1)
				(type default)
			)
			(layer "F.Fab")
		)
		(fp_line
			(start 0.120396 0.2794)
			(end -0.12065 0.2794)
			(stroke
				(width 0.1)
				(type default)
			)
			(layer "F.Fab")
		)
		(fp_line
			(start 0.120396 0.3048)
			(end 0.120396 0.2794)
			(stroke
				(width 0.1)
				(type default)
			)
			(layer "F.Fab")
		)
		(fp_line
			(start 0.12065 -0.3048)
			(end 0.67945 -0.3048)
			(stroke
				(width 0.1)
				(type default)
			)
			(layer "F.Fab")
		)
		(fp_line
			(start 0.12065 -0.2794)
			(end 0.12065 -0.3048)
			(stroke
				(width 0.1)
				(type default)
			)
			(layer "F.Fab")
		)
		(fp_line
			(start 0.67945 -0.3048)
			(end 0.67945 0.3048)
			(stroke
				(width 0.1)
				(type default)
			)
			(layer "F.Fab")
		)
		(fp_line
			(start 0.67945 0.3048)
			(end 0.120396 0.3048)
			(stroke
				(width 0.1)
				(type default)
			)
			(layer "F.Fab")
		)
		(pad "1" smd circle
			(at -0.40005 0)
			(size 0 0)
			(layers "F.Cu" "F.Mask" "F.Paste")
			(net "P3V3_AUX")
		)
		(pad "2" smd circle
			(at 0.40005 0)
			(size 0 0)
			(layers "F.Cu" "F.Mask" "F.Paste")
			(net "SSD2_LED_R")
		)
	)
	(footprint ""
		(layer "F.Cu")
		(at 214.454486 -216.270586)
		(property "Reference" "R4877"
			(at 0 0 0)
			(layer "F.SilkS")
			(hide yes)
			(effects
				(font
					(size 1.27 1.27)
				)
			)
		)
		(property "Value" ""
			(at 0 0 0)
			(layer "F.Fab")
			(effects
				(font
					(size 1.27 1.27)
				)
			)
		)
		(duplicate_pad_numbers_are_jumpers no)
		(fp_line
			(start -0.7874 -0.4064)
			(end 0.7874 -0.4064)
			(stroke
				(width 0.1524)
				(type default)
			)
			(layer "F.SilkS")
		)
		(fp_line
			(start -0.7874 0.4064)
			(end -0.7874 -0.4064)
			(stroke
				(width 0.1524)
				(type default)
			)
			(layer "F.SilkS")
		)
		(fp_line
			(start 0.7874 -0.4064)
			(end 0.7874 0.4064)
			(stroke
				(width 0.1524)
				(type default)
			)
			(layer "F.SilkS")
		)
		(fp_line
			(start 0.7874 0.4064)
			(end -0.7874 0.4064)
			(stroke
				(width 0.1524)
				(type default)
			)
			(layer "F.SilkS")
		)
		(fp_line
			(start -0.67945 -0.305054)
			(end -0.12065 -0.305054)
			(stroke
				(width 0.1)
				(type default)
			)
			(layer "F.Fab")
		)
		(fp_line
			(start -0.67945 0.3048)
			(end -0.67945 -0.305054)
			(stroke
				(width 0.1)
				(type default)
			)
			(layer "F.Fab")
		)
		(fp_line
			(start -0.12065 -0.305054)
			(end -0.12065 -0.2794)
			(stroke
				(width 0.1)
				(type default)
			)
			(layer "F.Fab")
		)
		(fp_line
			(start -0.12065 -0.2794)
			(end 0.12065 -0.2794)
			(stroke
				(width 0.1)
				(type default)
			)
			(layer "F.Fab")
		)
		(fp_line
			(start -0.12065 0.2794)
			(end -0.12065 0.3048)
			(stroke
				(width 0.1)
				(type default)
			)
			(layer "F.Fab")
		)
		(fp_line
			(start -0.12065 0.3048)
			(end -0.67945 0.3048)
			(stroke
				(width 0.1)
				(type default)
			)
			(layer "F.Fab")
		)
		(fp_line
			(start 0.120396 0.2794)
			(end -0.12065 0.2794)
			(stroke
				(width 0.1)
				(type default)
			)
			(layer "F.Fab")
		)
		(fp_line
			(start 0.120396 0.3048)
			(end 0.120396 0.2794)
			(stroke
				(width 0.1)
				(type default)
			)
			(layer "F.Fab")
		)
		(fp_line
			(start 0.12065 -0.3048)
			(end 0.67945 -0.3048)
			(stroke
				(width 0.1)
				(type default)
			)
			(layer "F.Fab")
		)
		(fp_line
			(start 0.12065 -0.2794)
			(end 0.12065 -0.3048)
			(stroke
				(width 0.1)
				(type default)
			)
			(layer "F.Fab")
		)
		(fp_line
			(start 0.67945 -0.3048)
			(end 0.67945 0.3048)
			(stroke
				(width 0.1)
				(type default)
			)
			(layer "F.Fab")
		)
		(fp_line
			(start 0.67945 0.3048)
			(end 0.120396 0.3048)
			(stroke
				(width 0.1)
				(type default)
			)
			(layer "F.Fab")
		)
		(pad "1" smd circle
			(at -0.40005 0)
			(size 0 0)
			(layers "F.Cu" "F.Mask" "F.Paste")
			(net "P1V2_AUX")
		)
		(pad "2" smd circle
			(at 0.40005 0)
			(size 0 0)
			(layers "F.Cu" "F.Mask" "F.Paste")
			(net "SMB_NIC6_SCL")
		)
	)
)
